(kicad_pcb
	(version 20260206)
	(generator "pcbnew")
	(generator_version "10.0")
	(general
		(thickness 1.6)
		(legacy_teardrops no)
	)
	(paper "A4")
	(title_block
		(title "03242023_DA0F0TMBIJ0_F0T_Motherboard_J_brd_V01_OCP.brd")
		(comment 1 "Grand Teton / footprints 1689-1689 of 6105")
	)
	(layers
		(0 "F.Cu" signal "TOP")
		(4 "In1.Cu" signal "GND")
		(6 "In2.Cu" signal "IN1")
		(8 "In3.Cu" signal "GND1")
		(10 "In4.Cu" signal "IN2")
		(12 "In5.Cu" signal "GND2")
		(14 "In6.Cu" signal "IN3")
		(16 "In7.Cu" signal "GND3")
		(18 "In8.Cu" signal "VCC")
		(20 "In9.Cu" signal "VCC1")
		(22 "In10.Cu" signal "GND4")
		(24 "In11.Cu" signal "IN4")
		(26 "In12.Cu" signal "GND5")
		(28 "In13.Cu" signal "IN5")
		(30 "In14.Cu" signal "GND6")
		(32 "In15.Cu" signal "IN6")
		(34 "In16.Cu" signal "GND7")
		(2 "B.Cu" signal "BOTTOM")
		(9 "F.Adhes" user "F.Adhesive")
		(11 "B.Adhes" user "B.Adhesive")
		(13 "F.Paste" user "Package Geometry/Pastemask Top")
		(15 "B.Paste" user "Package Geometry/Pastemask Bottom")
		(5 "F.SilkS" user "Ref Des/Silkscreen Top")
		(7 "B.SilkS" user "Ref Des/Silkscreen Bottom")
		(1 "F.Mask" user "Board Geometry/Soldermask Top")
		(3 "B.Mask" user "Board Geometry/Soldermask Bottom")
		(17 "Dwgs.User" user "User.Drawings")
		(19 "Cmts.User" user "User.Comments")
		(21 "Eco1.User" user "User.Eco1")
		(23 "Eco2.User" user "User.Eco2")
		(25 "Edge.Cuts" user "Board Geometry/Outline")
		(27 "Margin" user)
		(31 "F.CrtYd" user "Package Geometry/Place Bound Top")
		(29 "B.CrtYd" user "Package Geometry/Place Bound Bottom")
		(35 "F.Fab" user "Ref Des/Assembly Top")
		(33 "B.Fab" user "Ref Des/Assembly Bottom")
	)
	(footprint ""
		(layer "F.Cu")
		(at 366.3696 -409.194 180)
		(property "Reference" "R4738"
			(at 0 0 180)
			(layer "F.SilkS")
			(hide yes)
			(effects
				(font
					(size 1.27 1.27)
				)
			)
		)
		(property "Value" ""
			(at 0 0 180)
			(layer "F.Fab")
			(effects
				(font
					(size 1.27 1.27)
				)
			)
		)
		(duplicate_pad_numbers_are_jumpers no)
		(fp_line
			(start 0.7874 0.4064)
			(end -0.7874 0.4064)
			(stroke
				(width 0.1524)
				(type default)
			)
			(layer "F.SilkS")
		)
		(fp_line
			(start 0.7874 -0.4064)
			(end 0.7874 0.4064)
			(stroke
				(width 0.1524)
				(type default)
			)
			(layer "F.SilkS")
		)
		(fp_line
			(start -0.7874 0.4064)
			(end -0.7874 -0.4064)
			(stroke
				(width 0.1524)
				(type default)
			)
			(layer "F.SilkS")
		)
		(fp_line
			(start -0.7874 -0.4064)
			(end 0.7874 -0.4064)
			(stroke
				(width 0.1524)
				(type default)
			)
			(layer "F.SilkS")
		)
		(fp_line
			(start 0.67945 0.3048)
			(end 0.120396 0.3048)
			(stroke
				(width 0.1)
				(type default)
			)
			(layer "F.Fab")
		)
		(fp_line
			(start 0.67945 -0.3048)
			(end 0.67945 0.3048)
			(stroke
				(width 0.1)
				(type default)
			)
			(layer "F.Fab")
		)
		(fp_line
			(start 0.12065 -0.2794)
			(end 0.12065 -0.3048)
			(stroke
				(width 0.1)
				(type default)
			)
			(layer "F.Fab")
		)
		(fp_line
			(start 0.12065 -0.3048)
			(end 0.67945 -0.3048)
			(stroke
				(width 0.1)
				(type default)
			)
			(layer "F.Fab")
		)
		(fp_line
			(start 0.120396 0.3048)
			(end 0.120396 0.2794)
			(stroke
				(width 0.1)
				(type default)
			)
			(layer "F.Fab")
		)
		(fp_line
			(start 0.120396 0.2794)
			(end -0.12065 0.2794)
			(stroke
				(width 0.1)
				(type default)
			)
			(layer "F.Fab")
		)
		(fp_line
			(start -0.12065 0.3048)
			(end -0.67945 0.3048)
			(stroke
				(width 0.1)
				(type default)
			)
			(layer "F.Fab")
		)
		(fp_line
			(start -0.12065 0.2794)
			(end -0.12065 0.3048)
			(stroke
				(width 0.1)
				(type default)
			)
			(layer "F.Fab")
		)
		(fp_line
			(start -0.12065 -0.2794)
			(end 0.12065 -0.2794)
			(stroke
				(width 0.1)
				(type default)
			)
			(layer "F.Fab")
		)
		(fp_line
			(start -0.12065 -0.305054)
			(end -0.12065 -0.2794)
			(stroke
				(width 0.1)
				(type default)
			)
			(layer "F.Fab")
		)
		(fp_line
			(start -0.67945 0.3048)
			(end -0.67945 -0.305054)
			(stroke
				(width 0.1)
				(type default)
			)
			(layer "F.Fab")
		)
		(fp_line
			(start -0.67945 -0.305054)
			(end -0.12065 -0.305054)
			(stroke
				(width 0.1)
				(type default)
			)
			(layer "F.Fab")
		)
		(pad "1" smd circle
			(at -0.40005 0 180)
			(size 0 0)
			(layers "F.Cu" "F.Mask" "F.Paste")
			(net "PRSNT_CABLE_SWB_B1_N")
		)
		(pad "2" smd circle
			(at 0.40005 0 180)
			(size 0 0)
			(layers "F.Cu" "F.Mask" "F.Paste")
			(net "GND")
		)
	)
)
